# TIMECARD (Time Appliance Project (Time Card)) — schematic netlist excerpt (pin names and nets, part order shuffled) for the footprints in the layout excerpt that follows; sources: Cadence DE-HDL packaged netlist, KiCad conversion of R4006-B0001-02_R01.brd

U26  TPS54824RNVR_VQFN18  TPS54424RNVT  pkg QFN18_138_P0197_V1  page 29
  BOOT  = XP1R0V_BT
  VIN_1  = VIN_XP1R0V
  PGND_1  = SG
  PGND_2  = SG
  PGND_3  = SG
  SW_1  = XP1R0V_SW
  SW_2  = XP1R0V_SW
  PGND_4  = SG
  PGND_5  = SG
  PGND_6  = SG
  VIN_2  = VIN_XP1R0V
  AGND  = XP1R0V_AGND
  \rt/clk\  = XP1R0V_RT
  FB  = XP1R0V_FB_R_TO_AGND
  COMP  = XP1R0V_COMP
  \ss/trk\  = XP1R0V_SS
  EN  = UNNAMED_523_CAPACITOR_I7_1
  PGOOD  = XP1R0V_PG

(kicad_pcb
	(version 20260206)
	(generator "pcbnew")
	(generator_version "10.0")
	(general
		(thickness 1.6)
		(legacy_teardrops no)
	)
	(paper "A4")
	(title_block
		(title "timecard-production-celestica-r4006 — R4006-B0001-02_R01.brd")
		(comment 1 "Time Appliance Project (Time Card) / footprints 523-523 of 1113")
	)
	(layers
		(0 "F.Cu" signal "TOP")
		(4 "In1.Cu" signal "L02_GND1")
		(6 "In2.Cu" signal "L03_SIG1")
		(8 "In3.Cu" signal "L04_GND2")
		(10 "In4.Cu" signal "L05_VCC1")
		(12 "In5.Cu" signal "L06_VCC2")
		(14 "In6.Cu" signal "L07_GND3")
		(16 "In7.Cu" signal "L08_SIG2")
		(18 "In8.Cu" signal "L09_GND4")
		(2 "B.Cu" signal "BOTTOM")
		(9 "F.Adhes" user "F.Adhesive")
		(11 "B.Adhes" user "B.Adhesive")
		(13 "F.Paste" user "Package Geometry/Pastemask Top")
		(15 "B.Paste" user "Package Geometry/Pastemask Bottom")
		(5 "F.SilkS" user "Ref Des/Silkscreen Top")
		(7 "B.SilkS" user "Ref Des/Silkscreen Bottom")
		(1 "F.Mask" user "Board Geometry/Soldermask Top")
		(3 "B.Mask" user "Board Geometry/Soldermask Bottom")
		(17 "Dwgs.User" user "User.Drawings")
		(19 "Cmts.User" user "User.Comments")
		(21 "Eco1.User" user "User.Eco1")
		(23 "Eco2.User" user "User.Eco2")
		(25 "Edge.Cuts" user "Board Geometry/Outline")
		(27 "Margin" user)
		(31 "F.CrtYd" user "Package Geometry/Place Bound Top")
		(29 "B.CrtYd" user "Package Geometry/Place Bound Bottom")
		(35 "F.Fab" user "Ref Des/Assembly Top")
		(33 "B.Fab" user "Ref Des/Assembly Bottom")
	)
	(footprint ""
		(layer "F.Cu")
		(at 141.605 -54.737)
		(property "Reference" "U26"
			(at 0.127 -2.75463 0)
			(unlocked yes)
			(layer "F.SilkS")
			(effects
				(font
					(size 0.7874 0.5842)
					(thickness 0.1524)
				)
			)
		)
		(property "Value" ""
			(at 0 0 0)
			(layer "F.Fab")
			(effects
				(font
					(size 1.27 1.27)
				)
			)
		)
		(property "User Part Number" "PARTNUM*"
			(at 0.33782 5.715254 0)
			(unlocked yes)
			(layer "Cmts.User")
			(hide yes)
			(effects
				(font
					(size 0.7874 0.5842)
					(thickness 0.1524)
				)
			)
		)
		(property "Device Type" "TPS54824RNVR_VQFN18-G220-10657A"
			(at 0.33782 4.521454 0)
			(unlocked yes)
			(layer "F.Fab")
			(hide yes)
			(effects
				(font
					(size 0.7874 0.5842)
					(thickness 0.1524)
				)
			)
		)
		(duplicate_pad_numbers_are_jumpers no)
		(fp_line
			(start -2.208784 -2.208784)
			(end 2.208784 -2.208784)
			(stroke
				(width 0.1)
				(type default)
			)
			(layer "F.SilkS")
		)
		(fp_line
			(start -2.208784 2.200148)
			(end -2.208784 -2.208784)
			(stroke
				(width 0.1)
				(type default)
			)
			(layer "F.SilkS")
		)
		(fp_line
			(start 2.208784 -2.208784)
			(end 2.208784 2.200148)
			(stroke
				(width 0.1)
				(type default)
			)
			(layer "F.SilkS")
		)
		(fp_line
			(start 2.208784 2.200148)
			(end -2.208784 2.200148)
			(stroke
				(width 0.1)
				(type default)
			)
			(layer "F.SilkS")
		)
		(fp_poly
			(pts
				(arc
					(start -2.576068 -0.99314)
					(mid -3.592068 -0.99314)
					(end -2.576068 -0.99314)
				)
			)
			(stroke
				(width 0)
				(type default)
			)
			(fill yes)
			(layer "F.SilkS")
		)
		(fp_rect
			(start -2.462784 2.454148)
			(end 2.462784 -2.462784)
			(stroke
				(width 0)
				(type default)
			)
			(fill no)
			(layer "F.CrtYd")
		)
		(fp_line
			(start -1.800098 -1.800098)
			(end 1.800098 -1.800098)
			(stroke
				(width 0.1)
				(type default)
			)
			(layer "F.Fab")
		)
		(fp_line
			(start -1.800098 1.800098)
			(end -1.800098 -1.800098)
			(stroke
				(width 0.1)
				(type default)
			)
			(layer "F.Fab")
		)
		(fp_line
			(start 1.800098 -1.800098)
			(end 1.800098 1.800098)
			(stroke
				(width 0.1)
				(type default)
			)
			(layer "F.Fab")
		)
		(fp_line
			(start 1.800098 1.800098)
			(end -1.800098 1.800098)
			(stroke
				(width 0.1)
				(type default)
			)
			(layer "F.Fab")
		)
		(fp_circle
			(center -2.60604 -1.09982)
			(end -2.09804 -1.09982)
			(stroke
				(width 0.1)
				(type default)
			)
			(fill no)
			(layer "F.Fab")
		)
		(fp_text user "18"
			(at -2.413 -2.81305 0)
			(unlocked yes)
			(layer "F.SilkS")
			(effects
				(font
					(size 0.635 0.4064)
					(thickness 0.1524)
				)
			)
		)
		(fp_text user "5"
			(at -2.286 2.90195 0)
			(unlocked yes)
			(layer "F.SilkS")
			(effects
				(font
					(size 0.635 0.4064)
					(thickness 0.1524)
				)
			)
		)
		(fp_text user "6"
			(at -0.333502 3.002788 0)
			(unlocked yes)
			(layer "F.SilkS")
			(effects
				(font
					(size 0.635 0.4064)
					(thickness 0.1524)
				)
			)
		)
		(fp_text user "7"
			(at 0.484124 3.003296 0)
			(unlocked yes)
			(layer "F.SilkS")
			(effects
				(font
					(size 0.635 0.4064)
					(thickness 0.1524)
				)
			)
		)
		(fp_text user "8"
			(at 2.413 3.02895 0)
			(unlocked yes)
			(layer "F.SilkS")
			(effects
				(font
					(size 0.635 0.4064)
					(thickness 0.1524)
				)
			)
		)
		(fp_text user "13"
			(at 2.667 -2.50825 0)
			(unlocked yes)
			(layer "F.SilkS")
			(effects
				(font
					(size 0.635 0.4064)
					(thickness 0.1524)
				)
			)
		)
		(fp_text user "12"
			(at 3.175 -1.23825 0)
			(unlocked yes)
			(layer "F.SilkS")
			(effects
				(font
					(size 0.635 0.4064)
					(thickness 0.1524)
				)
			)
		)
		(fp_text user "5"
			(at -2.286 1.29667 0)
			(unlocked yes)
			(layer "F.Fab")
			(effects
				(font
					(size 0.7874 0.5842)
					(thickness 0.1524)
				)
			)
		)
		(fp_text user "18"
			(at -1.884934 -2.4638 0)
			(unlocked yes)
			(layer "F.Fab")
			(effects
				(font
					(size 0.7874 0.5842)
					(thickness 0.1524)
				)
			)
		)
		(fp_text user "6"
			(at -1.397 2.56667 0)
			(unlocked yes)
			(layer "F.Fab")
			(effects
				(font
					(size 0.7874 0.5842)
					(thickness 0.1524)
				)
			)
		)
		(fp_text user "13"
			(at 0.889 -2.25933 0)
			(unlocked yes)
			(layer "F.Fab")
			(effects
				(font
					(size 0.7874 0.5842)
					(thickness 0.1524)
				)
			)
		)
		(fp_text user "7"
			(at 1.524 2.43967 0)
			(unlocked yes)
			(layer "F.Fab")
			(effects
				(font
					(size 0.7874 0.5842)
					(thickness 0.1524)
				)
			)
		)
		(fp_text user "8"
			(at 2.286 1.29667 0)
			(unlocked yes)
			(layer "F.Fab")
			(effects
				(font
					(size 0.7874 0.5842)
					(thickness 0.1524)
				)
			)
		)
		(fp_text user "12"
			(at 2.54 -1.49733 0)
			(unlocked yes)
			(layer "F.Fab")
			(effects
				(font
					(size 0.7874 0.5842)
					(thickness 0.1524)
				)
			)
		)
		(pad "1" smd rect
			(at -1.649984 -0.94996)
			(size 0.6096 0.3048)
			(layers "F.Cu" "F.Mask" "F.Paste")
			(net "XP1R0V_BT")
		)
		(pad "2" smd rect
			(at -1.374902 -0.350012)
			(size 1.143 0.4064)
			(layers "F.Cu" "F.Mask" "F.Paste")
			(net "VIN_XP1R0V")
		)
		(pad "3" smd rect
			(at -1.374902 0.299974)
			(size 1.143 0.3048)
			(layers "F.Cu" "F.Mask" "F.Paste")
			(net "SG")
		)
		(pad "4" smd rect
			(at -1.374902 0.849884)
			(size 1.143 0.3048)
			(layers "F.Cu" "F.Mask" "F.Paste")
			(net "SG")
		)
		(pad "5" smd rect
			(at -1.374902 1.400048)
			(size 1.143 0.3048)
			(layers "F.Cu" "F.Mask" "F.Paste")
			(net "SG")
		)
		(pad "6" smd rect
			(at -0.32512 0.599948)
			(size 0.2032 2.6924)
			(layers "F.Cu" "F.Mask" "F.Paste")
			(net "XP1R0V_SW")
		)
		(pad "7" smd rect
			(at 0.32512 0.599948)
			(size 0.2032 2.6924)
			(layers "F.Cu" "F.Mask" "F.Paste")
			(net "XP1R0V_SW")
		)
		(pad "8" smd rect
			(at 1.374902 1.400048)
			(size 1.143 0.3048)
			(layers "F.Cu" "F.Mask" "F.Paste")
			(net "SG")
		)
		(pad "9" smd rect
			(at 1.374902 0.849884)
			(size 1.143 0.3048)
			(layers "F.Cu" "F.Mask" "F.Paste")
			(net "SG")
		)
		(pad "10" smd rect
			(at 1.374902 0.299974)
			(size 1.143 0.3048)
			(layers "F.Cu" "F.Mask" "F.Paste")
			(net "SG")
		)
		(pad "11" smd rect
			(at 1.374902 -0.350012)
			(size 1.143 0.4064)
			(layers "F.Cu" "F.Mask" "F.Paste")
			(net "VIN_XP1R0V")
		)
		(pad "12" smd rect
			(at 1.649984 -0.94996)
			(size 0.6096 0.3048)
			(layers "F.Cu" "F.Mask" "F.Paste")
			(net "XP1R0V_AGND")
		)
		(pad "13" smd rect
			(at 1.374902 -1.649984)
			(size 0.508 0.6096)
			(layers "F.Cu" "F.Mask" "F.Paste")
			(net "XP1R0V_RT")
		)
		(pad "14" smd rect
			(at 0.750062 -1.649984)
			(size 0.254 0.6096)
			(layers "F.Cu" "F.Mask" "F.Paste")
			(net "XP1R0V_FB_R_TO_AGND")
		)
		(pad "15" smd rect
			(at 0.249936 -1.649984)
			(size 0.254 0.6096)
			(layers "F.Cu" "F.Mask" "F.Paste")
			(net "XP1R0V_COMP")
		)
		(pad "16" smd rect
			(at -0.249936 -1.649984)
			(size 0.254 0.6096)
			(layers "F.Cu" "F.Mask" "F.Paste")
			(net "XP1R0V_SS")
		)
		(pad "17" smd rect
			(at -0.750062 -1.649984)
			(size 0.254 0.6096)
			(layers "F.Cu" "F.Mask" "F.Paste")
			(net "UNNAMED_523_CAPACITOR_I7_1")
		)
		(pad "18" smd rect
			(at -1.374902 -1.649984)
			(size 0.508 0.6096)
			(layers "F.Cu" "F.Mask" "F.Paste")
			(net "XP1R0V_PG")
		)
	)
)
